(kicad_pcb
	(version 20260206)
	(generator "pcbnew")
	(generator_version "10.0")
	(general
		(thickness 1.6)
		(legacy_teardrops no)
	)
	(paper "A4")
	(title_block
		(title "panther-plus-userver — 13130-1b_20150205.brd")
		(comment 1 "Honey Badger (Wiwynn) / footprints 681-688 of 1509")
	)
	(layers
		(0 "F.Cu" signal "TOP")
		(4 "In1.Cu" signal "L2")
		(6 "In2.Cu" signal "L3")
		(8 "In3.Cu" signal "L4")
		(10 "In4.Cu" signal "L5")
		(12 "In5.Cu" signal "L6")
		(14 "In6.Cu" signal "L7")
		(16 "In7.Cu" signal "L8")
		(18 "In8.Cu" signal "L9")
		(20 "In9.Cu" signal "L10")
		(22 "In10.Cu" signal "L11")
		(2 "B.Cu" signal "BOTTOM")
		(9 "F.Adhes" user "F.Adhesive")
		(11 "B.Adhes" user "B.Adhesive")
		(13 "F.Paste" user "Package Geometry/Pastemask Top")
		(15 "B.Paste" user "Package Geometry/Pastemask Bottom")
		(5 "F.SilkS" user "Ref Des/Silkscreen Top")
		(7 "B.SilkS" user "Ref Des/Silkscreen Bottom")
		(1 "F.Mask" user "Board Geometry/Soldermask Top")
		(3 "B.Mask" user "Board Geometry/Soldermask Bottom")
		(17 "Dwgs.User" user "User.Drawings")
		(19 "Cmts.User" user "User.Comments")
		(21 "Eco1.User" user "User.Eco1")
		(23 "Eco2.User" user "User.Eco2")
		(25 "Edge.Cuts" user "Board Geometry/Outline")
		(27 "Margin" user)
		(31 "F.CrtYd" user "Package Geometry/Place Bound Top")
		(29 "B.CrtYd" user "Package Geometry/Place Bound Bottom")
		(35 "F.Fab" user "Ref Des/Assembly Top")
		(33 "B.Fab" user "Ref Des/Assembly Bottom")
	)
	(footprint ""
		(layer "F.Cu")
		(at 55.372 -23.495 -90)
		(property "Reference" "R145"
			(at 0 0 270)
			(layer "F.SilkS")
			(hide yes)
			(effects
				(font
					(size 1.27 1.27)
				)
			)
		)
		(property "Value" "4K7R2F-GP"
			(at 0.064008 -3.993896 270)
			(unlocked yes)
			(layer "F.Fab")
			(hide yes)
			(effects
				(font
					(size 1.016 1.016)
					(thickness 0.1524)
				)
			)
		)
		(property "Device Type" "R402H16"
			(at 0.064008 -5.517896 270)
			(unlocked yes)
			(layer "F.Fab")
			(hide yes)
			(effects
				(font
					(size 1.016 1.016)
					(thickness 0.1524)
				)
			)
		)
		(duplicate_pad_numbers_are_jumpers no)
		(fp_rect
			(start -0.381 0.8382)
			(end 0.381 -0.8382)
			(stroke
				(width 0)
				(type default)
			)
			(fill no)
			(layer "F.CrtYd")
		)
		(fp_rect
			(start -0.381 0.8382)
			(end 0.381 -0.8382)
			(stroke
				(width 0)
				(type default)
			)
			(fill no)
			(layer "F.Fab")
		)
		(pad "1" smd custom
			(at 0 -0.4318 270)
			(size 0.127 0.127)
			(layers "F.Cu" "F.Mask" "F.Paste")
			(net "P3V3_CPU")
			(options
				(clearance outline)
				(anchor circle)
			)
			(primitives
				(gr_poly
					(pts
						(arc
							(start -0.2032 -0.2794)
							(mid -0.239121 -0.264521)
							(end -0.254 -0.2286)
						)
						(arc
							(start -0.254 0.2286)
							(mid -0.239121 0.264521)
							(end -0.2032 0.2794)
						)
						(arc
							(start 0.2032 0.2794)
							(mid 0.239121 0.264521)
							(end 0.254 0.2286)
						)
						(arc
							(start 0.254 -0.2286)
							(mid 0.239121 -0.264521)
							(end 0.2032 -0.2794)
						)
					)
					(width 0)
					(fill yes)
				)
			)
		)
		(pad "2" smd custom
			(at 0 0.4318 270)
			(size 0.127 0.127)
			(layers "F.Cu" "F.Mask" "F.Paste")
			(net "SPI_GBE_HOLD#")
			(options
				(clearance outline)
				(anchor circle)
			)
			(primitives
				(gr_poly
					(pts
						(arc
							(start -0.2032 -0.2794)
							(mid -0.239121 -0.264521)
							(end -0.254 -0.2286)
						)
						(arc
							(start -0.254 0.2286)
							(mid -0.239121 0.264521)
							(end -0.2032 0.2794)
						)
						(arc
							(start 0.2032 0.2794)
							(mid 0.239121 0.264521)
							(end 0.254 0.2286)
						)
						(arc
							(start 0.254 -0.2286)
							(mid 0.239121 -0.264521)
							(end 0.2032 -0.2794)
						)
					)
					(width 0)
					(fill yes)
				)
			)
		)
	)
	(footprint ""
		(layer "F.Cu")
		(at 26.416 -50.038 -90)
		(property "Reference" "PC70"
			(at 0 0 270)
			(layer "F.SilkS")
			(hide yes)
			(effects
				(font
					(size 1.27 1.27)
				)
			)
		)
		(property "Value" "SCD22U10V2KX-1GP"
			(at 1.8923 -1.2065 270)
			(unlocked yes)
			(layer "F.Fab")
			(hide yes)
			(effects
				(font
					(size 1.016 1.016)
					(thickness 0.1524)
				)
			)
		)
		(property "Device Type" "C402H22"
			(at 1.8923 -2.7305 270)
			(unlocked yes)
			(layer "F.Fab")
			(hide yes)
			(effects
				(font
					(size 1.016 1.016)
					(thickness 0.1524)
				)
			)
		)
		(duplicate_pad_numbers_are_jumpers no)
		(fp_rect
			(start -0.381 0.7366)
			(end 0.381 -0.7366)
			(stroke
				(width 0)
				(type default)
			)
			(fill no)
			(layer "F.CrtYd")
		)
		(fp_rect
			(start -0.381 0.7366)
			(end 0.381 -0.7366)
			(stroke
				(width 0)
				(type default)
			)
			(fill no)
			(layer "F.Fab")
		)
		(pad "1" smd custom
			(at 0 -0.4572 270)
			(size 0.1143 0.1143)
			(layers "F.Cu" "F.Mask" "F.Paste")
			(net "VR_PVCCP_ISUMP")
			(options
				(clearance outline)
				(anchor circle)
			)
			(primitives
				(gr_poly
					(pts
						(arc
							(start -0.254 -0.1778)
							(mid -0.239121 -0.213721)
							(end -0.2032 -0.2286)
						)
						(arc
							(start 0.2032 -0.2286)
							(mid 0.239121 -0.213721)
							(end 0.254 -0.1778)
						)
						(arc
							(start 0.254 0.1778)
							(mid 0.239121 0.213721)
							(end 0.2032 0.2286)
						)
						(arc
							(start -0.2032 0.2286)
							(mid -0.239121 0.213721)
							(end -0.254 0.1778)
						)
					)
					(width 0)
					(fill yes)
				)
			)
		)
		(pad "2" smd custom
			(at 0 0.4572 270)
			(size 0.1143 0.1143)
			(layers "F.Cu" "F.Mask" "F.Paste")
			(net "VR_PVCCP_ISUMN")
			(options
				(clearance outline)
				(anchor circle)
			)
			(primitives
				(gr_poly
					(pts
						(arc
							(start -0.254 -0.1778)
							(mid -0.239121 -0.213721)
							(end -0.2032 -0.2286)
						)
						(arc
							(start 0.2032 -0.2286)
							(mid 0.239121 -0.213721)
							(end 0.254 -0.1778)
						)
						(arc
							(start 0.254 0.1778)
							(mid 0.239121 0.213721)
							(end 0.2032 0.2286)
						)
						(arc
							(start -0.2032 0.2286)
							(mid -0.239121 0.213721)
							(end -0.254 0.1778)
						)
					)
					(width 0)
					(fill yes)
				)
			)
		)
	)
	(footprint ""
		(layer "F.Cu")
		(at 66.929 -12.573 -90)
		(property "Reference" "C338"
			(at 0 0 270)
			(layer "F.SilkS")
			(hide yes)
			(effects
				(font
					(size 1.27 1.27)
				)
			)
		)
		(property "Value" "SCD1U10V2KX-5GP"
			(at 1.8923 -1.2065 270)
			(unlocked yes)
			(layer "F.Fab")
			(hide yes)
			(effects
				(font
					(size 1.016 1.016)
					(thickness 0.1524)
				)
			)
		)
		(property "Device Type" "C402H22"
			(at 1.8923 -2.7305 270)
			(unlocked yes)
			(layer "F.Fab")
			(hide yes)
			(effects
				(font
					(size 1.016 1.016)
					(thickness 0.1524)
				)
			)
		)
		(duplicate_pad_numbers_are_jumpers no)
		(fp_rect
			(start -0.381 0.7366)
			(end 0.381 -0.7366)
			(stroke
				(width 0)
				(type default)
			)
			(fill no)
			(layer "F.CrtYd")
		)
		(fp_rect
			(start -0.381 0.7366)
			(end 0.381 -0.7366)
			(stroke
				(width 0)
				(type default)
			)
			(fill no)
			(layer "F.Fab")
		)
		(pad "1" smd custom
			(at 0 -0.4572 270)
			(size 0.1143 0.1143)
			(layers "F.Cu" "F.Mask" "F.Paste")
			(net "P3V3")
			(options
				(clearance outline)
				(anchor circle)
			)
			(primitives
				(gr_poly
					(pts
						(arc
							(start -0.254 -0.1778)
							(mid -0.239121 -0.213721)
							(end -0.2032 -0.2286)
						)
						(arc
							(start 0.2032 -0.2286)
							(mid 0.239121 -0.213721)
							(end 0.254 -0.1778)
						)
						(arc
							(start 0.254 0.1778)
							(mid 0.239121 0.213721)
							(end 0.2032 0.2286)
						)
						(arc
							(start -0.2032 0.2286)
							(mid -0.239121 0.213721)
							(end -0.254 0.1778)
						)
					)
					(width 0)
					(fill yes)
				)
			)
		)
		(pad "2" smd custom
			(at 0 0.4572 270)
			(size 0.1143 0.1143)
			(layers "F.Cu" "F.Mask" "F.Paste")
			(net "GND")
			(options
				(clearance outline)
				(anchor circle)
			)
			(primitives
				(gr_poly
					(pts
						(arc
							(start -0.254 -0.1778)
							(mid -0.239121 -0.213721)
							(end -0.2032 -0.2286)
						)
						(arc
							(start 0.2032 -0.2286)
							(mid 0.239121 -0.213721)
							(end 0.254 -0.1778)
						)
						(arc
							(start 0.254 0.1778)
							(mid 0.239121 0.213721)
							(end 0.2032 0.2286)
						)
						(arc
							(start -0.2032 0.2286)
							(mid -0.239121 0.213721)
							(end -0.254 0.1778)
						)
					)
					(width 0)
					(fill yes)
				)
			)
		)
	)
	(footprint ""
		(layer "F.Cu")
		(at 19.939 -20.828 -90)
		(property "Reference" "PR103"
			(at 0 0 270)
			(layer "F.SilkS")
			(hide yes)
			(effects
				(font
					(size 1.27 1.27)
				)
			)
		)
		(property "Value" "6K49R2D-GP"
			(at 1.7907 -1.1176 270)
			(unlocked yes)
			(layer "F.Fab")
			(hide yes)
			(effects
				(font
					(size 1.016 1.016)
					(thickness 0.1524)
				)
			)
		)
		(property "Device Type" "R402H16"
			(at 1.7907 -2.6416 270)
			(unlocked yes)
			(layer "F.Fab")
			(hide yes)
			(effects
				(font
					(size 1.016 1.016)
					(thickness 0.1524)
				)
			)
		)
		(duplicate_pad_numbers_are_jumpers no)
		(fp_rect
			(start -0.381 0.8382)
			(end 0.381 -0.8382)
			(stroke
				(width 0)
				(type default)
			)
			(fill no)
			(layer "F.CrtYd")
		)
		(fp_rect
			(start -0.381 0.8382)
			(end 0.381 -0.8382)
			(stroke
				(width 0)
				(type default)
			)
			(fill no)
			(layer "F.Fab")
		)
		(pad "1" smd custom
			(at 0 -0.4318 270)
			(size 0.127 0.127)
			(layers "F.Cu" "F.Mask" "F.Paste")
			(net "P1V0_VFB_R")
			(options
				(clearance outline)
				(anchor circle)
			)
			(primitives
				(gr_poly
					(pts
						(arc
							(start -0.2032 -0.2794)
							(mid -0.239121 -0.264521)
							(end -0.254 -0.2286)
						)
						(arc
							(start -0.254 0.2286)
							(mid -0.239121 0.264521)
							(end -0.2032 0.2794)
						)
						(arc
							(start 0.2032 0.2794)
							(mid 0.239121 0.264521)
							(end 0.254 0.2286)
						)
						(arc
							(start 0.254 -0.2286)
							(mid 0.239121 -0.264521)
							(end 0.2032 -0.2794)
						)
					)
					(width 0)
					(fill yes)
				)
			)
		)
		(pad "2" smd custom
			(at 0 0.4318 270)
			(size 0.127 0.127)
			(layers "F.Cu" "F.Mask" "F.Paste")
			(net "P1V0_VFB")
			(options
				(clearance outline)
				(anchor circle)
			)
			(primitives
				(gr_poly
					(pts
						(arc
							(start -0.2032 -0.2794)
							(mid -0.239121 -0.264521)
							(end -0.254 -0.2286)
						)
						(arc
							(start -0.254 0.2286)
							(mid -0.239121 0.264521)
							(end -0.2032 0.2794)
						)
						(arc
							(start 0.2032 0.2794)
							(mid 0.239121 0.264521)
							(end 0.254 0.2286)
						)
						(arc
							(start 0.254 -0.2286)
							(mid 0.239121 -0.264521)
							(end 0.2032 -0.2794)
						)
					)
					(width 0)
					(fill yes)
				)
			)
		)
	)
	(footprint ""
		(layer "F.Cu")
		(at 75.4888 -37.084 180)
		(property "Reference" "TP33"
			(at 0 0 180)
			(layer "F.SilkS")
			(hide yes)
			(effects
				(font
					(size 1.27 1.27)
				)
			)
		)
		(property "Value" "TPAD28-1-GP-U"
			(at 0.0508 -1.9304 180)
			(unlocked yes)
			(layer "F.Fab")
			(hide yes)
			(effects
				(font
					(size 1.016 1.016)
					(thickness 0.1524)
				)
			)
		)
		(property "Device Type" "TPAD28-1-U"
			(at 0.0508 -3.4544 180)
			(unlocked yes)
			(layer "F.Fab")
			(hide yes)
			(effects
				(font
					(size 1.016 1.016)
					(thickness 0.1524)
				)
			)
		)
		(duplicate_pad_numbers_are_jumpers no)
		(fp_poly
			(pts
				(arc
					(start -0.3556 0)
					(mid 0.3556 0)
					(end -0.3556 0)
				)
			)
			(stroke
				(width 0)
				(type default)
			)
			(fill no)
			(layer "F.CrtYd")
		)
		(fp_poly
			(pts
				(arc
					(start -0.9525 0)
					(mid 0.9525 0)
					(end -0.9525 0)
				)
			)
			(stroke
				(width 0)
				(type default)
			)
			(fill no)
			(layer "F.Fab")
		)
		(pad "1" smd circle
			(at 0 0 180)
			(size 0.7112 0.7112)
			(layers "F.Cu" "F.Mask" "F.Paste")
			(net "USB_OC#")
		)
	)
	(footprint ""
		(layer "F.Cu")
		(at 31.75 -13.335)
		(property "Reference" "U29"
			(at 0 0 0)
			(layer "F.SilkS")
			(hide yes)
			(effects
				(font
					(size 1.27 1.27)
				)
			)
		)
		(property "Value" "2N7002DW-7F-GP"
			(at -2.5654 1.1049 0)
			(unlocked yes)
			(layer "F.Fab")
			(hide yes)
			(effects
				(font
					(size 1.016 1.016)
					(thickness 0.1524)
				)
			)
		)
		(property "Device Type" "SOT-363H44"
			(at -2.5654 -0.4191 0)
			(unlocked yes)
			(layer "F.Fab")
			(hide yes)
			(effects
				(font
					(size 1.016 1.016)
					(thickness 0.1524)
				)
			)
		)
		(duplicate_pad_numbers_are_jumpers no)
		(fp_poly
			(pts
				(xy -0.6731 1.4351) (xy -0.9779 1.7399) (xy -0.381 1.7399) (xy -0.3683 1.7399) (xy -0.381 1.7272)
			)
			(stroke
				(width 0)
				(type default)
			)
			(fill yes)
			(layer "F.SilkS")
		)
		(fp_poly
			(pts
				(xy 1.2573 0.8763) (xy 1.2573 -0.8763) (xy 0.9525 -0.8763) (xy 0.9525 -1.4351) (xy -0.9525 -1.4351)
				(xy -0.9525 -0.8763) (xy -1.2573 -0.8763) (xy -1.2573 0.8763) (xy -0.9525 0.8763) (xy -0.9525 1.4351)
				(xy 0.9525 1.4351) (xy 0.9525 0.8763)
			)
			(stroke
				(width 0)
				(type default)
			)
			(fill no)
			(layer "F.CrtYd")
		)
		(fp_poly
			(pts
				(xy 1.2573 0.8763) (xy 1.2573 -0.8763) (xy 0.9525 -0.8763) (xy 0.9525 -1.4351) (xy -0.9525 -1.4351)
				(xy -0.9525 -0.8763) (xy -1.2573 -0.8763) (xy -1.2573 0.8763) (xy -0.9525 0.8763) (xy -0.9525 1.4351)
				(xy 0.9525 1.4351) (xy 0.9525 0.8763)
			)
			(stroke
				(width 0)
				(type default)
			)
			(fill no)
			(layer "F.Fab")
		)
		(pad "1" smd rect
			(at -0.65024 0.8255)
			(size 0.3556 0.9652)
			(layers "F.Cu" "F.Mask" "F.Paste")
			(net "BMC_I2C_CLK")
		)
		(pad "2" smd rect
			(at 0 0.8255)
			(size 0.3556 0.9652)
			(layers "F.Cu" "F.Mask" "F.Paste")
			(net "PICE_GF_I2C_SW_EN")
		)
		(pad "3" smd rect
			(at 0.65024 0.8255)
			(size 0.3556 0.9652)
			(layers "F.Cu" "F.Mask" "F.Paste")
			(net "PCIE_GF_I2C_DATA")
		)
		(pad "4" smd rect
			(at 0.65024 -0.8255)
			(size 0.3556 0.9652)
			(layers "F.Cu" "F.Mask" "F.Paste")
			(net "BMC_I2C_DATA")
		)
		(pad "5" smd rect
			(at 0 -0.8255)
			(size 0.3556 0.9652)
			(layers "F.Cu" "F.Mask" "F.Paste")
			(net "PICE_GF_I2C_SW_EN")
		)
		(pad "6" smd rect
			(at -0.65024 -0.8255)
			(size 0.3556 0.9652)
			(layers "F.Cu" "F.Mask" "F.Paste")
			(net "PCIE_GF_I2C_CLK")
		)
	)
	(footprint ""
		(layer "F.Cu")
		(at 46.863 -37.5158)
		(property "Reference" "C314"
			(at 0 0 0)
			(layer "F.SilkS")
			(hide yes)
			(effects
				(font
					(size 1.27 1.27)
				)
			)
		)
		(property "Value" "SCD1U10V2KX-5GP"
			(at 1.8923 -1.2065 0)
			(unlocked yes)
			(layer "F.Fab")
			(hide yes)
			(effects
				(font
					(size 1.016 1.016)
					(thickness 0.1524)
				)
			)
		)
		(property "Device Type" "C402H22"
			(at 1.8923 -2.7305 0)
			(unlocked yes)
			(layer "F.Fab")
			(hide yes)
			(effects
				(font
					(size 1.016 1.016)
					(thickness 0.1524)
				)
			)
		)
		(duplicate_pad_numbers_are_jumpers no)
		(fp_rect
			(start -0.381 0.7366)
			(end 0.381 -0.7366)
			(stroke
				(width 0)
				(type default)
			)
			(fill no)
			(layer "F.CrtYd")
		)
		(fp_rect
			(start -0.381 0.7366)
			(end 0.381 -0.7366)
			(stroke
				(width 0)
				(type default)
			)
			(fill no)
			(layer "F.Fab")
		)
		(pad "1" smd custom
			(at 0 -0.4572)
			(size 0.1143 0.1143)
			(layers "F.Cu" "F.Mask" "F.Paste")
			(net "P3V3_STBY")
			(options
				(clearance outline)
				(anchor circle)
			)
			(primitives
				(gr_poly
					(pts
						(arc
							(start -0.254 -0.1778)
							(mid -0.239121 -0.213721)
							(end -0.2032 -0.2286)
						)
						(arc
							(start 0.2032 -0.2286)
							(mid 0.239121 -0.213721)
							(end 0.254 -0.1778)
						)
						(arc
							(start 0.254 0.1778)
							(mid 0.239121 0.213721)
							(end 0.2032 0.2286)
						)
						(arc
							(start -0.2032 0.2286)
							(mid -0.239121 0.213721)
							(end -0.254 0.1778)
						)
					)
					(width 0)
					(fill yes)
				)
			)
		)
		(pad "2" smd custom
			(at 0 0.4572)
			(size 0.1143 0.1143)
			(layers "F.Cu" "F.Mask" "F.Paste")
			(net "GND")
			(options
				(clearance outline)
				(anchor circle)
			)
			(primitives
				(gr_poly
					(pts
						(arc
							(start -0.254 -0.1778)
							(mid -0.239121 -0.213721)
							(end -0.2032 -0.2286)
						)
						(arc
							(start 0.2032 -0.2286)
							(mid 0.239121 -0.213721)
							(end 0.254 -0.1778)
						)
						(arc
							(start 0.254 0.1778)
							(mid 0.239121 0.213721)
							(end 0.2032 0.2286)
						)
						(arc
							(start -0.2032 0.2286)
							(mid -0.239121 0.213721)
							(end -0.254 0.1778)
						)
					)
					(width 0)
					(fill yes)
				)
			)
		)
	)
	(footprint ""
		(layer "F.Cu")
		(at 73.025 -40.005)
		(property "Reference" "R92"
			(at 0 0 0)
			(layer "F.SilkS")
			(hide yes)
			(effects
				(font
					(size 1.27 1.27)
				)
			)
		)
		(property "Value" "10MR3F-GP"
			(at -0.0254 -2.5146 0)
			(unlocked yes)
			(layer "F.Fab")
			(hide yes)
			(effects
				(font
					(size 1.016 1.016)
					(thickness 0.1524)
				)
			)
		)
		(property "Device Type" "R603H22"
			(at -0.0254 -4.0386 0)
			(unlocked yes)
			(layer "F.Fab")
			(hide yes)
			(effects
				(font
					(size 1.016 1.016)
					(thickness 0.1524)
				)
			)
		)
		(duplicate_pad_numbers_are_jumpers no)
		(fp_line
			(start -0.2032 0)
			(end -0.4191 0)
			(stroke
				(width 0.2032)
				(type default)
			)
			(layer "F.SilkS")
		)
		(fp_line
			(start 0.4318 0)
			(end 0.2032 0)
			(stroke
				(width 0.2032)
				(type default)
			)
			(layer "F.SilkS")
		)
		(fp_rect
			(start -0.635 1.1811)
			(end 0.635 -1.1811)
			(stroke
				(width 0)
				(type default)
			)
			(fill no)
			(layer "F.CrtYd")
		)
		(fp_rect
			(start -0.635 1.1811)
			(end 0.635 -1.1811)
			(stroke
				(width 0)
				(type default)
			)
			(fill no)
			(layer "F.Fab")
		)
		(pad "1" smd custom
			(at 0 -0.6604)
			(size 0.19685 0.19685)
			(layers "F.Cu" "F.Mask" "F.Paste")
			(net "RTC_X1PAD")
			(options
				(clearance outline)
				(anchor circle)
			)
			(primitives
				(gr_poly
					(pts
						(arc
							(start 0.508 -0.2921)
							(mid 0.478242 -0.363942)
							(end 0.4064 -0.3937)
						)
						(arc
							(start -0.4064 -0.3937)
							(mid -0.478242 -0.363942)
							(end -0.508 -0.2921)
						)
						(arc
							(start -0.508 0.2921)
							(mid -0.478242 0.363942)
							(end -0.4064 0.3937)
						)
						(arc
							(start 0.4064 0.3937)
							(mid 0.478242 0.363942)
							(end 0.508 0.2921)
						)
					)
					(width 0)
					(fill yes)
				)
			)
		)
		(pad "2" smd custom
			(at 0 0.6604)
			(size 0.19685 0.19685)
			(layers "F.Cu" "F.Mask" "F.Paste")
			(net "RTC_X2PAD")
			(options
				(clearance outline)
				(anchor circle)
			)
			(primitives
				(gr_poly
					(pts
						(arc
							(start 0.508 -0.2921)
							(mid 0.478242 -0.363942)
							(end 0.4064 -0.3937)
						)
						(arc
							(start -0.4064 -0.3937)
							(mid -0.478242 -0.363942)
							(end -0.508 -0.2921)
						)
						(arc
							(start -0.508 0.2921)
							(mid -0.478242 0.363942)
							(end -0.4064 0.3937)
						)
						(arc
							(start 0.4064 0.3937)
							(mid 0.478242 0.363942)
							(end 0.508 0.2921)
						)
					)
					(width 0)
					(fill yes)
				)
			)
		)
	)
)
